FILE_TYPE = CONNECTIVITY;
{Allegro Design Entry HDL 17.2-2016 S081 (4005846) 1/11/2022}
"PAGE_NUMBER" = 59;
0"NC";
1"GND\g";
2"GND\g";
3"GND\g";
4"GND\g";
5"GND\g";
6"GND\g";
7"GND\g";
8"GND\g";
%"GENOA_SP5"
"34","(-7975,3500)","0","pure_quanta","I1";
;
LOCATION"U26"
$SEC"34"
CDS_SEC"34"
PART_TYPE"SMLF"
MATERIAL"IO"
VALUE"SOCKET6096_13568-001"
PART_NUMBER"DGA^6000030"
CDS_LIB"pure_quanta"
CDS_LMAN_SYM_OUTLINE"-400,3050,400,-3050"
NEEDS_NO_SIZE"TRUE";
"VSS_BV45"
$PN"BV45"2;
"VSS_BV44"
$PN"BV44"2;
"VSS_BV43"
$PN"BV43"2;
"VSS_BV39"
$PN"BV39"2;
"VSS_BV34"
$PN"BV34"2;
"VSS_BV33"
$PN"BV33"2;
"VSS_BV32"
$PN"BV32"2;
"VSS_BV31"
$PN"BV31"2;
"VSS_BV30"
$PN"BV30"2;
"VSS_BV29"
$PN"BV29"2;
"VSS_BV28"
$PN"BV28"2;
"VSS_BV27"
$PN"BV27"2;
"VSS_BV26"
$PN"BV26"2;
"VSS_BV25"
$PN"BV25"2;
"VSS_BV24"
$PN"BV24"2;
"VSS_BV23"
$PN"BV23"2;
"VSS_BV17"
$PN"BV17"2;
"VSS_BV15"
$PN"BV15"2;
"VSS_BV10"
$PN"BV10"2;
"VSS_BV8"
$PN"BV8"2;
"VSS_BV3"
$PN"BV3"2;
"VSS_BU75"
$PN"BU75"2;
"VSS_BU72"
$PN"BU72"2;
"VSS_BU70"
$PN"BU70"2;
"VSS_BU68"
$PN"BU68"2;
"VSS_BU65"
$PN"BU65"2;
"VSS_BU63"
$PN"BU63"2;
"VSS_BU61"
$PN"BU61"2;
"VSS_BU58"
$PN"BU58"2;
"VSS_BU56"
$PN"BU56"2;
"VSS_BU54"
$PN"BU54"2;
"VSS_BU51"
$PN"BU51"2;
"VSS_BU48"
$PN"BU48"2;
"VSS_BU45"
$PN"BU45"2;
"VSS_BU42"
$PN"BU42"2;
"VSS_BU41"
$PN"BU41"2;
"VSS_BU40"
$PN"BU40"2;
"VSS_BU36"
$PN"BU36"2;
"VSS_BU35"
$PN"BU35"2;
"VSS_BU34"
$PN"BU34"2;
"VSS_BU31"
$PN"BU31"2;
"VSS_BU28"
$PN"BU28"2;
"VSS_BU25"
$PN"BU25"2;
"VSS_BU22"
$PN"BU22"2;
"VSS_BU20"
$PN"BU20"2;
"VSS_BU18"
$PN"BU18"2;
"VSS_BU15"
$PN"BU15"2;
"VSS_BU13"
$PN"BU13"2;
"VSS_BU11"
$PN"BU11"2;
"VSS_BU8"
$PN"BU8"2;
"VSS_BU6"
$PN"BU6"2;
"VSS_BU4"
$PN"BU4"2;
"VSS_BU1"
$PN"BU1"2;
"VSS_BT73"
$PN"BT73"2;
"VSS_BT72"
$PN"BT72"2;
"VSS_BT71"
$PN"BT71"2;
"VSS_BT69"
$PN"BT69"2;
"VSS_BT68"
$PN"BT68"2;
"VSS_BT66"
$PN"BT66"2;
"VSS_BT65"
$PN"BT65"2;
"VSS_BT64"
$PN"BT64"2;
"VSS_BT62"
$PN"BT62"2;
"VSS_BT61"
$PN"BT61"2;
"VSS_BT59"
$PN"BT59"2;
"VSS_BT58"
$PN"BT58"2;
"VSS_BT57"
$PN"BT57"2;
"VSS_BT55"
$PN"BT55"2;
"VSS_BT54"
$PN"BT54"2;
"VSS_BT51"
$PN"BT51"2;
"VSS_BT48"
$PN"BT48"2;
"VSS_BT45"
$PN"BT45"2;
"VSS_BT42"
$PN"BT42"2;
"VSS_BT39"
$PN"BT39"2;
"VSS_BT37"
$PN"BT37"2;
"VSS_BT34"
$PN"BT34"2;
"VSS_BT31"
$PN"BT31"2;
"VSS_BT28"
$PN"BT28"2;
"VSS_BT25"
$PN"BT25"2;
"VSS_BT22"
$PN"BT22"2;
"VSS_BT21"
$PN"BT21"2;
"VSS_BT19"
$PN"BT19"2;
"VSS_BT18"
$PN"BT18"2;
"VSS_BT17"
$PN"BT17"2;
"VSS_BT15"
$PN"BT15"2;
"VSS_BT14"
$PN"BT14"2;
"VSS_BT12"
$PN"BT12"2;
"VSS_BT11"
$PN"BT11"2;
"VSS_BT10"
$PN"BT10"2;
"VSS_BT8"
$PN"BT8"2;
"VSS_BT7"
$PN"BT7"2;
"VSS_BT5"
$PN"BT5"2;
"VSS_BT4"
$PN"BT4"2;
"VSS_BT3"
$PN"BT3"2;
"VSS_BR75"
$PN"BR75"2;
"VSS_BR73"
$PN"BR73"2;
"VSS_BR70"
$PN"BR70"2;
"VSS_BR69"
$PN"BR69"2;
"VSS_BR68"
$PN"BR68"2;
"VSS_BR66"
$PN"BR66"2;
"VSS_BR63"
$PN"BR63"2;
"VSS_BR62"
$PN"BR62"2;
"VSS_BR61"
$PN"BR61"2;
"VSS_BR59"
$PN"BR59"2;
"VSS_BR56"
$PN"BR56"2;
"VSS_BR55"
$PN"BR55"2;
"VSS_BR51"
$PN"BR51"2;
"VSS_BR49"
$PN"BR49"2;
"VSS_BR47"
$PN"BR47"2;
"VSS_BR45"
$PN"BR45"2;
"VSS_BR43"
$PN"BR43"2;
"VSS_BR41"
$PN"BR41"2;
"VSS_BR36"
$PN"BR36"2;
"VSS_BR34"
$PN"BR34"2;
"VSS_BR32"
$PN"BR32"2;
"VSS_BR30"
$PN"BR30"2;
"VSS_BR28"
$PN"BR28"2;
"VSS_BR26"
$PN"BR26"2;
"VSS_BR24"
$PN"BR24"1;
"VSS_BR22"
$PN"BR22"1;
"VSS_BR21"
$PN"BR21"1;
"VSS_BR20"
$PN"BR20"1;
"VSS_BR17"
$PN"BR17"1;
"VSS_BR15"
$PN"BR15"1;
"VSS_BR14"
$PN"BR14"1;
"VSS_BR13"
$PN"BR13"1;
"VSS_BR10"
$PN"BR10"1;
"VSS_BR8"
$PN"BR8"1;
"VSS_BR7"
$PN"BR7"1;
"VSS_BR6"
$PN"BR6"1;
"VSS_BR3"
$PN"BR3"1;
"VSS_BR1"
$PN"BR1"1;
"VSS_BP73"
$PN"BP73"1;
"VSS_BP71"
$PN"BP71"1;
"VSS_BP68"
$PN"BP68"1;
"VSS_BP66"
$PN"BP66"1;
"VSS_BP64"
$PN"BP64"1;
"VSS_BP61"
$PN"BP61"1;
"VSS_BP59"
$PN"BP59"1;
"VSS_BP57"
$PN"BP57"1;
"VSS_BP54"
$PN"BP54"1;
"VSS_BP52"
$PN"BP52"1;
"VSS_BP50"
$PN"BP50"1;
"VSS_BP48"
$PN"BP48"1;
"VSS_BP46"
$PN"BP46"1;
"VSS_BP44"
$PN"BP44"1;
"VSS_BP42"
$PN"BP42"1;
"VSS_BP40"
$PN"BP40"1;
"VSS_BP37"
$PN"BP37"1;
"VSS_BP35"
$PN"BP35"1;
"VSS_BP33"
$PN"BP33"1;
"VSS_BP31"
$PN"BP31"1;
"VSS_BP29"
$PN"BP29"1;
"VSS_BP27"
$PN"BP27"1;
"VSS_BP25"
$PN"BP25"1;
"VSS_BP23"
$PN"BP23"1;
"VSS_BP19"
$PN"BP19"1;
"VSS_BP17"
$PN"BP17"1;
"VSS_BP15"
$PN"BP15"1;
"VSS_BP12"
$PN"BP12"1;
"VSS_BP10"
$PN"BP10"1;
"VSS_BP8"
$PN"BP8"1;
"VSS_BP5"
$PN"BP5"1;
"VSS_BP3"
$PN"BP3"1;
"VSS_BN75"
$PN"BN75"1;
"VSS_BN72"
$PN"BN72"1;
"VSS_BN70"
$PN"BN70"1;
"VSS_BN68"
$PN"BN68"1;
"VSS_BN65"
$PN"BN65"1;
"VSS_BN63"
$PN"BN63"1;
"VSS_BN61"
$PN"BN61"1;
"VSS_BN58"
$PN"BN58"1;
"VSS_BN56"
$PN"BN56"1;
"VSS_BN53"
$PN"BN53"1;
"VSS_BN51"
$PN"BN51"1;
"VSS_BN49"
$PN"BN49"1;
"VSS_BN47"
$PN"BN47"1;
"VSS_BN45"
$PN"BN45"1;
"VSS_BN43"
$PN"BN43"1;
"VSS_BN41"
$PN"BN41"1;
"VSS_BN36"
$PN"BN36"1;
"VSS_BN34"
$PN"BN34"1;
"VSS_BN32"
$PN"BN32"1;
"VSS_BN30"
$PN"BN30"1;
"VSS_BN28"
$PN"BN28"1;
"VSS_BN26"
$PN"BN26"1;
"VSS_BN24"
$PN"BN24"1;
"VSS_BN22"
$PN"BN22"1;
"VSS_BN20"
$PN"BN20"1;
"VSS_BN18"
$PN"BN18"1;
"VSS_BN15"
$PN"BN15"1;
"VSS_BN13"
$PN"BN13"1;
"VSS_BN11"
$PN"BN11"1;
"VSS_BN8"
$PN"BN8"1;
"VSS_BN6"
$PN"BN6"1;
"VSS_BN4"
$PN"BN4"1;
"VSS_BN1"
$PN"BN1"1;
"VSS_BM73"
$PN"BM73"1;
"VSS_BM68"
$PN"BM68"1;
"VSS_BM66"
$PN"BM66"1;
"VSS_BM61"
$PN"BM61"1;
"VSS_BM59"
$PN"BM59"1;
"VSS_BM54"
$PN"BM54"1;
"VSS_BM52"
$PN"BM52"1;
"VSS_BM50"
$PN"BM50"1;
"VSS_BM48"
$PN"BM48"1;
"VSS_BM46"
$PN"BM46"1;
"VSS_BM44"
$PN"BM44"1;
"VSS_BM42"
$PN"BM42"1;
"VSS_BM40"
$PN"BM40"1;
"VSS_BM37"
$PN"BM37"1;
"VSS_BM35"
$PN"BM35"1;
"VSS_BM33"
$PN"BM33"1;
"VSS_BM31"
$PN"BM31"1;
"VSS_BM29"
$PN"BM29"1;
"VSS_BM27"
$PN"BM27"1;
"VSS_BM25"
$PN"BM25"1;
"VSS_BM23"
$PN"BM23"1;
"VSS_BM17"
$PN"BM17"1;
"VSS_BM15"
$PN"BM15"1;
"VSS_BM10"
$PN"BM10"1;
"VSS_BM8"
$PN"BM8"1;
"VSS_BM3"
$PN"BM3"1;
"VSS_BL75"
$PN"BL75"1;
"VSS_BL72"
$PN"BL72"1;
"VSS_BL70"
$PN"BL70"1;
"VSS_BL68"
$PN"BL68"1;
"VSS_BL65"
$PN"BL65"1;
"VSS_BL63"
$PN"BL63"1;
"VSS_BL61"
$PN"BL61"1;
"VSS_BL58"
$PN"BL58"1;
"VSS_BL56"
$PN"BL56"1;
"VSS_BL53"
$PN"BL53"1;
"VSS_BL51"
$PN"BL51"1;
"VSS_BL49"
$PN"BL49"1;
"VSS_BL28"
$PN"BL28"1;
"VSS_BL26"
$PN"BL26"1;
"VSS_BV37"
$PN"BV37"2;
%"UNIVERSAL_GND"
"1","(-6675,475)","0","pure_quanta_power","I10";
;
CDS_LIB"pure_quanta_power"
HDL_POWER"GND";
"A"3;
%"UNIVERSAL_GND"
"1","(-7250,475)","0","pure_quanta_power","I11";
;
CDS_LIB"pure_quanta_power"
HDL_POWER"GND";
"A"2;
%"UNIVERSAL_GND"
"1","(-8700,450)","0","pure_quanta_power","I12";
;
CDS_LIB"pure_quanta_power"
HDL_POWER"GND";
"A"1;
%"GENOA_SP5"
"37","(-5950,3500)","0","pure_quanta","I2";
;
LOCATION"U26"
$SEC"37"
CDS_SEC"37"
PART_TYPE"SMLF"
MATERIAL"IO"
VALUE"SOCKET6096_13568-001"
PART_NUMBER"DGA^6000030"
CDS_LIB"pure_quanta"
CDS_LMAN_SYM_OUTLINE"-400,3050,400,-3050"
NEEDS_NO_SIZE"TRUE";
"VSS_CF33"
$PN"CF33"4;
"VSS_CF32"
$PN"CF32"4;
"VSS_CF31"
$PN"CF31"4;
"VSS_CF30"
$PN"CF30"4;
"VSS_CF29"
$PN"CF29"4;
"VSS_CF28"
$PN"CF28"4;
"VSS_CF27"
$PN"CF27"4;
"VSS_CF26"
$PN"CF26"4;
"VSS_CF25"
$PN"CF25"4;
"VSS_CF24"
$PN"CF24"4;
"VSS_CF23"
$PN"CF23"4;
"VSS_CF19"
$PN"CF19"4;
"VSS_CF17"
$PN"CF17"4;
"VSS_CF15"
$PN"CF15"4;
"VSS_CF12"
$PN"CF12"4;
"VSS_CF10"
$PN"CF10"4;
"VSS_CF8"
$PN"CF8"4;
"VSS_CF5"
$PN"CF5"4;
"VSS_CF3"
$PN"CF3"4;
"VSS_CE75"
$PN"CE75"4;
"VSS_CE72"
$PN"CE72"4;
"VSS_CE70"
$PN"CE70"4;
"VSS_CE68"
$PN"CE68"4;
"VSS_CE65"
$PN"CE65"4;
"VSS_CE63"
$PN"CE63"4;
"VSS_CE61"
$PN"CE61"4;
"VSS_CE58"
$PN"CE58"4;
"VSS_CE56"
$PN"CE56"4;
"VSS_CE54"
$PN"CE54"4;
"VSS_CE51"
$PN"CE51"4;
"VSS_CE48"
$PN"CE48"4;
"VSS_CE45"
$PN"CE45"4;
"VSS_CE42"
$PN"CE42"4;
"VSS_CE41"
$PN"CE41"4;
"VSS_CE40"
$PN"CE40"4;
"VSS_CE36"
$PN"CE36"4;
"VSS_CE35"
$PN"CE35"4;
"VSS_CE34"
$PN"CE34"4;
"VSS_CE31"
$PN"CE31"4;
"VSS_CE28"
$PN"CE28"4;
"VSS_CE25"
$PN"CE25"4;
"VSS_CE22"
$PN"CE22"4;
"VSS_CE20"
$PN"CE20"4;
"VSS_CE18"
$PN"CE18"4;
"VSS_CE15"
$PN"CE15"4;
"VSS_CE13"
$PN"CE13"4;
"VSS_CE11"
$PN"CE11"4;
"VSS_CE8"
$PN"CE8"4;
"VSS_CE6"
$PN"CE6"4;
"VSS_CE4"
$PN"CE4"4;
"VSS_CE1"
$PN"CE1"4;
"VSS_CD73"
$PN"CD73"4;
"VSS_CD68"
$PN"CD68"4;
"VSS_CD66"
$PN"CD66"4;
"VSS_CD61"
$PN"CD61"4;
"VSS_CD59"
$PN"CD59"4;
"VSS_CD54"
$PN"CD54"4;
"VSS_CD51"
$PN"CD51"4;
"VSS_CD48"
$PN"CD48"4;
"VSS_CD45"
$PN"CD45"4;
"VSS_CD42"
$PN"CD42"4;
"VSS_CD39"
$PN"CD39"4;
"VSS_CD37"
$PN"CD37"4;
"VSS_CD34"
$PN"CD34"4;
"VSS_CD31"
$PN"CD31"4;
"VSS_CD28"
$PN"CD28"4;
"VSS_CD25"
$PN"CD25"4;
"VSS_CD22"
$PN"CD22"4;
"VSS_CD17"
$PN"CD17"4;
"VSS_CD15"
$PN"CD15"4;
"VSS_CD10"
$PN"CD10"4;
"VSS_CD8"
$PN"CD8"4;
"VSS_CD3"
$PN"CD3"4;
"VSS_CC75"
$PN"CC75"4;
"VSS_CC72"
$PN"CC72"4;
"VSS_CC70"
$PN"CC70"4;
"VSS_CC68"
$PN"CC68"4;
"VSS_CC65"
$PN"CC65"4;
"VSS_CC63"
$PN"CC63"4;
"VSS_CC61"
$PN"CC61"4;
"VSS_CC58"
$PN"CC58"4;
"VSS_CC56"
$PN"CC56"4;
"VSS_CC54"
$PN"CC54"4;
"VSS_CC51"
$PN"CC51"4;
"VSS_CC48"
$PN"CC48"4;
"VSS_CC45"
$PN"CC45"4;
"VSS_CC42"
$PN"CC42"4;
"VSS_CC34"
$PN"CC34"4;
"VSS_CC31"
$PN"CC31"4;
"VSS_CC28"
$PN"CC28"4;
"VSS_CC25"
$PN"CC25"4;
"VSS_CC20"
$PN"CC20"4;
"VSS_CC18"
$PN"CC18"4;
"VSS_CC15"
$PN"CC15"4;
"VSS_CC13"
$PN"CC13"4;
"VSS_CC11"
$PN"CC11"4;
"VSS_CC8"
$PN"CC8"4;
"VSS_CC6"
$PN"CC6"4;
"VSS_CC4"
$PN"CC4"4;
"VSS_CC1"
$PN"CC1"4;
"VSS_CB73"
$PN"CB73"4;
"VSS_CB71"
$PN"CB71"4;
"VSS_CB68"
$PN"CB68"4;
"VSS_CB66"
$PN"CB66"4;
"VSS_CB64"
$PN"CB64"4;
"VSS_CB61"
$PN"CB61"4;
"VSS_CB59"
$PN"CB59"4;
"VSS_CB57"
$PN"CB57"4;
"VSS_CB53"
$PN"CB53"4;
"VSS_CB52"
$PN"CB52"4;
"VSS_CB51"
$PN"CB51"4;
"VSS_CB50"
$PN"CB50"4;
"VSS_CB49"
$PN"CB49"4;
"VSS_CB48"
$PN"CB48"4;
"VSS_CB47"
$PN"CB47"4;
"VSS_CB46"
$PN"CB46"4;
"VSS_CB45"
$PN"CB45"4;
"VSS_CB43"
$PN"CB43"3;
"VSS_CB42"
$PN"CB42"3;
"VSS_CB39"
$PN"CB39"3;
"VSS_CB37"
$PN"CB37"3;
"VSS_CB34"
$PN"CB34"3;
"VSS_CB33"
$PN"CB33"3;
"VSS_CB32"
$PN"CB32"3;
"VSS_CB31"
$PN"CB31"3;
"VSS_CB30"
$PN"CB30"3;
"VSS_CB29"
$PN"CB29"3;
"VSS_CB28"
$PN"CB28"3;
"VSS_CB27"
$PN"CB27"3;
"VSS_CB26"
$PN"CB26"3;
"VSS_CB25"
$PN"CB25"3;
"VSS_CB24"
$PN"CB24"3;
"VSS_CB23"
$PN"CB23"3;
"VSS_CB19"
$PN"CB19"3;
"VSS_CB17"
$PN"CB17"3;
"VSS_CB15"
$PN"CB15"3;
"VSS_CB12"
$PN"CB12"3;
"VSS_CB10"
$PN"CB10"3;
"VSS_CB8"
$PN"CB8"3;
"VSS_CB5"
$PN"CB5"3;
"VSS_CB3"
$PN"CB3"3;
"VSS_CA75"
$PN"CA75"3;
"VSS_CA70"
$PN"CA70"3;
"VSS_CA68"
$PN"CA68"3;
"VSS_CA63"
$PN"CA63"3;
"VSS_CA61"
$PN"CA61"3;
"VSS_CA56"
$PN"CA56"3;
"VSS_CA54"
$PN"CA54"3;
"VSS_CA51"
$PN"CA51"3;
"VSS_CA48"
$PN"CA48"3;
"VSS_CA45"
$PN"CA45"3;
"VSS_CA42"
$PN"CA42"3;
"VSS_CA41"
$PN"CA41"3;
"VSS_CA40"
$PN"CA40"3;
"VSS_CA36"
$PN"CA36"3;
"VSS_CA35"
$PN"CA35"3;
"VSS_CA34"
$PN"CA34"3;
"VSS_CA31"
$PN"CA31"3;
"VSS_CA28"
$PN"CA28"3;
"VSS_CA25"
$PN"CA25"3;
"VSS_CA22"
$PN"CA22"3;
"VSS_CA20"
$PN"CA20"3;
"VSS_CA15"
$PN"CA15"3;
"VSS_CA13"
$PN"CA13"3;
"VSS_CA8"
$PN"CA8"3;
"VSS_CA6"
$PN"CA6"3;
"VSS_CA1"
$PN"CA1"3;
"VSS_BY73"
$PN"BY73"3;
"VSS_BY71"
$PN"BY71"3;
"VSS_BY68"
$PN"BY68"3;
"VSS_BY66"
$PN"BY66"3;
"VSS_BY64"
$PN"BY64"3;
"VSS_BY61"
$PN"BY61"3;
"VSS_BY59"
$PN"BY59"3;
"VSS_BY57"
$PN"BY57"3;
"VSS_BY54"
$PN"BY54"3;
"VSS_BY51"
$PN"BY51"3;
"VSS_BY48"
$PN"BY48"3;
"VSS_BY45"
$PN"BY45"3;
"VSS_BY42"
$PN"BY42"3;
"VSS_BY39"
$PN"BY39"3;
"VSS_BY37"
$PN"BY37"3;
"VSS_BY34"
$PN"BY34"3;
"VSS_BY31"
$PN"BY31"3;
"VSS_BY28"
$PN"BY28"3;
"VSS_BY25"
$PN"BY25"3;
"VSS_BY22"
$PN"BY22"3;
"VSS_BY19"
$PN"BY19"3;
"VSS_BY17"
$PN"BY17"3;
"VSS_BY15"
$PN"BY15"3;
"VSS_BY12"
$PN"BY12"3;
"VSS_BY10"
$PN"BY10"3;
"VSS_BY8"
$PN"BY8"3;
"VSS_BY5"
$PN"BY5"3;
"VSS_BY3"
$PN"BY3"3;
"VSS_BW75"
$PN"BW75"3;
"VSS_BW72"
$PN"BW72"3;
"VSS_BW70"
$PN"BW70"3;
"VSS_BW68"
$PN"BW68"3;
"VSS_BW65"
$PN"BW65"3;
"VSS_BW63"
$PN"BW63"3;
"VSS_BW61"
$PN"BW61"3;
"VSS_BW58"
$PN"BW58"3;
"VSS_BW56"
$PN"BW56"3;
"VSS_BW54"
$PN"BW54"3;
"VSS_BW51"
$PN"BW51"3;
"VSS_BW48"
$PN"BW48"3;
"VSS_BW45"
$PN"BW45"3;
"VSS_BW42"
$PN"BW42"3;
"VSS_BW34"
$PN"BW34"3;
"VSS_BW31"
$PN"BW31"3;
"VSS_BW28"
$PN"BW28"3;
"VSS_BW22"
$PN"BW22"3;
"VSS_BW20"
$PN"BW20"3;
"VSS_BW18"
$PN"BW18"3;
"VSS_BW15"
$PN"BW15"3;
"VSS_BW13"
$PN"BW13"3;
"VSS_BW11"
$PN"BW11"3;
"VSS_BW8"
$PN"BW8"3;
"VSS_BW6"
$PN"BW6"3;
"VSS_BW4"
$PN"BW4"3;
"VSS_BW1"
$PN"BW1"3;
"VSS_BV73"
$PN"BV73"3;
"VSS_BV68"
$PN"BV68"3;
"VSS_BV66"
$PN"BV66"3;
"VSS_BV61"
$PN"BV61"3;
"VSS_BV59"
$PN"BV59"3;
"VSS_BV53"
$PN"BV53"3;
"VSS_BV52"
$PN"BV52"3;
"VSS_BV51"
$PN"BV51"3;
"VSS_BV50"
$PN"BV50"3;
"VSS_BV49"
$PN"BV49"3;
"VSS_BV48"
$PN"BV48"3;
"VSS_BV47"
$PN"BV47"3;
"VSS_BV46"
$PN"BV46"3;
%"GENOA_SP5"
"38","(-3875,3475)","0","pure_quanta","I3";
;
LOCATION"U26"
$SEC"38"
CDS_SEC"38"
PART_TYPE"SMLF"
MATERIAL"IO"
VALUE"SOCKET6096_13568-001"
PART_NUMBER"DGA^6000030"
CDS_LIB"pure_quanta"
CDS_LMAN_SYM_OUTLINE"-400,3050,400,-3050"
NEEDS_NO_SIZE"TRUE";
"VSS_CP19"
$PN"CP19"6;
"VSS_CP17"
$PN"CP17"6;
"VSS_CP15"
$PN"CP15"6;
"VSS_CP12"
$PN"CP12"6;
"VSS_CP10"
$PN"CP10"6;
"VSS_CP8"
$PN"CP8"6;
"VSS_CP5"
$PN"CP5"6;
"VSS_CP3"
$PN"CP3"6;
"VSS_CN75"
$PN"CN75"6;
"VSS_CN70"
$PN"CN70"6;
"VSS_CN68"
$PN"CN68"6;
"VSS_CN63"
$PN"CN63"6;
"VSS_CN61"
$PN"CN61"6;
"VSS_CN51"
$PN"CN51"6;
"VSS_CN48"
$PN"CN48"6;
"VSS_CN45"
$PN"CN45"6;
"VSS_CN42"
$PN"CN42"6;
"VSS_CN34"
$PN"CN34"6;
"VSS_CN31"
$PN"CN31"6;
"VSS_CN28"
$PN"CN28"6;
"VSS_CN25"
$PN"CN25"6;
"VSS_CN15"
$PN"CN15"6;
"VSS_CN13"
$PN"CN13"6;
"VSS_CN8"
$PN"CN8"6;
"VSS_CN6"
$PN"CN6"6;
"VSS_CN1"
$PN"CN1"6;
"VSS_CM73"
$PN"CM73"6;
"VSS_CM71"
$PN"CM71"6;
"VSS_CM68"
$PN"CM68"6;
"VSS_CM59"
$PN"CM59"6;
"VSS_CM57"
$PN"CM57"6;
"VSS_CM53"
$PN"CM53"6;
"VSS_CM52"
$PN"CM52"6;
"VSS_CM51"
$PN"CM51"6;
"VSS_CM49"
$PN"CM49"6;
"VSS_CM48"
$PN"CM48"6;
"VSS_CM47"
$PN"CM47"6;
"VSS_CM46"
$PN"CM46"6;
"VSS_CM45"
$PN"CM45"6;
"VSS_CM44"
$PN"CM44"6;
"VSS_CM33"
$PN"CM33"6;
"VSS_CM32"
$PN"CM32"6;
"VSS_CM31"
$PN"CM31"6;
"VSS_CM30"
$PN"CM30"6;
"VSS_CM29"
$PN"CM29"6;
"VSS_CM28"
$PN"CM28"6;
"VSS_CM23"
$PN"CM23"6;
"VSS_CM19"
$PN"CM19"6;
"VSS_CM17"
$PN"CM17"6;
"VSS_CM15"
$PN"CM15"6;
"VSS_CM12"
$PN"CM12"6;
"VSS_CM10"
$PN"CM10"6;
"VSS_CM8"
$PN"CM8"6;
"VSS_CL72"
$PN"CL72"6;
"VSS_CL70"
$PN"CL70"6;
"VSS_CL68"
$PN"CL68"6;
"VSS_CL65"
$PN"CL65"6;
"VSS_CL63"
$PN"CL63"6;
"VSS_CL61"
$PN"CL61"6;
"VSS_CL58"
$PN"CL58"6;
"VSS_CL56"
$PN"CL56"6;
"VSS_CL48"
$PN"CL48"6;
"VSS_CL45"
$PN"CL45"6;
"VSS_CL42"
$PN"CL42"6;
"VSS_CL41"
$PN"CL41"6;
"VSS_CL40"
$PN"CL40"6;
"VSS_CL36"
$PN"CL36"6;
"VSS_CL35"
$PN"CL35"6;
"VSS_CL34"
$PN"CL34"6;
"VSS_CL31"
$PN"CL31"6;
"VSS_CL25"
$PN"CL25"6;
"VSS_CL22"
$PN"CL22"6;
"VSS_CL20"
$PN"CL20"6;
"VSS_CL18"
$PN"CL18"6;
"VSS_CL15"
$PN"CL15"6;
"VSS_CL13"
$PN"CL13"6;
"VSS_CL11"
$PN"CL11"6;
"VSS_CL8"
$PN"CL8"6;
"VSS_CL6"
$PN"CL6"6;
"VSS_CL4"
$PN"CL4"6;
"VSS_CL1"
$PN"CL1"6;
"VSS_CK73"
$PN"CK73"6;
"VSS_CK68"
$PN"CK68"6;
"VSS_CK66"
$PN"CK66"6;
"VSS_CK61"
$PN"CK61"6;
"VSS_CK59"
$PN"CK59"6;
"VSS_CK54"
$PN"CK54"6;
"VSS_CK53"
$PN"CK53"6;
"VSS_CK52"
$PN"CK52"6;
"VSS_CK51"
$PN"CK51"6;
"VSS_CK50"
$PN"CK50"6;
"VSS_CK49"
$PN"CK49"6;
"VSS_CK48"
$PN"CK48"6;
"VSS_CK45"
$PN"CK45"6;
"VSS_CK44"
$PN"CK44"6;
"VSS_CK43"
$PN"CK43"6;
"VSS_CK42"
$PN"CK42"5;
"VSS_CK39"
$PN"CK39"5;
"VSS_CK37"
$PN"CK37"5;
"VSS_CK34"
$PN"CK34"5;
"VSS_CK32"
$PN"CK32"5;
"VSS_CK28"
$PN"CK28"5;
"VSS_CK27"
$PN"CK27"5;
"VSS_CK26"
$PN"CK26"5;
"VSS_CK25"
$PN"CK25"5;
"VSS_CK24"
$PN"CK24"5;
"VSS_CK23"
$PN"CK23"5;
"VSS_CK22"
$PN"CK22"5;
"VSS_CK8"
$PN"CK8"5;
"VSS_CK3"
$PN"CK3"5;
"VSS_CJ75"
$PN"CJ75"5;
"VSS_CJ72"
$PN"CJ72"5;
"VSS_CJ70"
$PN"CJ70"5;
"VSS_CJ68"
$PN"CJ68"5;
"VSS_CJ65"
$PN"CJ65"5;
"VSS_CJ56"
$PN"CJ56"5;
"VSS_CJ45"
$PN"CJ45"5;
"VSS_CJ42"
$PN"CJ42"5;
"VSS_CJ41"
$PN"CJ41"5;
"VSS_CJ40"
$PN"CJ40"5;
"VSS_CJ36"
$PN"CJ36"5;
"VSS_CJ35"
$PN"CJ35"5;
"VSS_CJ18"
$PN"CJ18"5;
"VSS_CJ15"
$PN"CJ15"5;
"VSS_CJ13"
$PN"CJ13"5;
"VSS_CJ11"
$PN"CJ11"5;
"VSS_CJ8"
$PN"CJ8"5;
"VSS_CJ6"
$PN"CJ6"5;
"VSS_CH66"
$PN"CH66"5;
"VSS_CH64"
$PN"CH64"5;
"VSS_CH61"
$PN"CH61"5;
"VSS_CH59"
$PN"CH59"5;
"VSS_CH57"
$PN"CH57"5;
"VSS_CH54"
$PN"CH54"5;
"VSS_CH37"
$PN"CH37"5;
"VSS_CH34"
$PN"CH34"5;
"VSS_CH31"
$PN"CH31"5;
"VSS_CH28"
$PN"CH28"5;
"VSS_CH25"
$PN"CH25"5;
"VSS_CH22"
$PN"CH22"5;
"VSS_CH8"
$PN"CH8"5;
"VSS_CH5"
$PN"CH5"5;
"VSS_CH3"
$PN"CH3"5;
"VSS_CG75"
$PN"CG75"5;
"VSS_CG70"
$PN"CG70"5;
"VSS_CG68"
$PN"CG68"5;
"VSS_CG63"
$PN"CG63"5;
"VSS_CG61"
$PN"CG61"5;
"VSS_CG56"
$PN"CG56"5;
"VSS_CG54"
$PN"CG54"5;
"VSS_CG51"
$PN"CG51"5;
"VSS_CG48"
$PN"CG48"5;
"VSS_CG45"
$PN"CG45"5;
"VSS_CG34"
$PN"CG34"5;
"VSS_CG31"
$PN"CG31"5;
"VSS_CG28"
$PN"CG28"5;
"VSS_CG25"
$PN"CG25"5;
"VSS_CG22"
$PN"CG22"5;
"VSS_CG20"
$PN"CG20"5;
"VSS_CG15"
$PN"CG15"5;
"VSS_CG13"
$PN"CG13"5;
"VSS_CG8"
$PN"CG8"5;
"VSS_CG6"
$PN"CG6"5;
"VSS_CG1"
$PN"CG1"5;
"VSS_CF73"
$PN"CF73"5;
"VSS_CF71"
$PN"CF71"5;
"VSS_CF68"
$PN"CF68"5;
"VSS_CF66"
$PN"CF66"5;
"VSS_CF64"
$PN"CF64"5;
"VSS_CF61"
$PN"CF61"5;
"VSS_CF59"
$PN"CF59"5;
"VSS_CF57"
$PN"CF57"5;
"VSS_CF53"
$PN"CF53"5;
"VSS_CF52"
$PN"CF52"5;
"VSS_CF51"
$PN"CF51"5;
"VSS_CF50"
$PN"CF50"5;
"VSS_CF49"
$PN"CF49"5;
"VSS_CF48"
$PN"CF48"5;
"VSS_CF47"
$PN"CF47"5;
"VSS_CF45"
$PN"CF45"5;
"VSS_CF44"
$PN"CF44"5;
"VSS_CF43"
$PN"CF43"5;
"VSS_CF42"
$PN"CF42"5;
"VSS_CF39"
$PN"CF39"5;
"VSS_CF37"
$PN"CF37"5;
"VSS_CF34"
$PN"CF34"5;
"VSS_CH19"
$PN"CH19"5;
"VSS_CH51"
$PN"CH51"5;
"VSS_CJ4"
$PN"CJ4"5;
"VSS_CL28"
$PN"CL28"6;
"VSS_CL54"
$PN"CL54"6;
"VSS_CM5"
$PN"CM5"6;
"VSS_CM27"
$PN"CM27"6;
"VSS_CM43"
$PN"CM43"6;
"VSS_CH17"
$PN"CH17"5;
"VSS_CH48"
$PN"CH48"5;
"VSS_CJ1"
$PN"CJ1"5;
"VSS_CJ34"
$PN"CJ34"5;
"VSS_CL51"
$PN"CL51"6;
"VSS_CM3"
$PN"CM3"6;
"VSS_CM26"
$PN"CM26"6;
"VSS_CM42"
$PN"CM42"6;
"VSS_CH15"
$PN"CH15"5;
"VSS_CH45"
$PN"CH45"5;
"VSS_CH73"
$PN"CH73"5;
"VSS_CJ31"
$PN"CJ31"5;
"VSS_CJ63"
$PN"CJ63"5;
"VSS_CL75"
$PN"CL75"6;
"VSS_CM25"
$PN"CM25"6;
"VSS_CM39"
$PN"CM39"6;
"VSS_CM66"
$PN"CM66"6;
"VSS_CH12"
$PN"CH12"5;
"VSS_CH42"
$PN"CH42"5;
"VSS_CH71"
$PN"CH71"5;
"VSS_CJ23"
$PN"CJ23"5;
"VSS_CJ61"
$PN"CJ61"5;
"VSS_CK17"
$PN"CK17"5;
"VSS_CM24"
$PN"CM24"6;
"VSS_CM37"
$PN"CM37"6;
"VSS_CM64"
$PN"CM64"6;
"VSS_CN22"
$PN"CN22"6;
"VSS_CH10"
$PN"CH10"5;
"VSS_CH39"
$PN"CH39"5;
"VSS_CH68"
$PN"CH68"5;
"VSS_CJ20"
$PN"CJ20"5;
"VSS_CJ58"
$PN"CJ58"5;
"VSS_CK15"
$PN"CK15"5;
"VSS_CK33"
$PN"CK33"5;
"VSS_CM34"
$PN"CM34"6;
"VSS_CM61"
$PN"CM61"6;
"VSS_CN20"
$PN"CN20"6;
"VSS_CN56"
$PN"CN56"6;
%"GENOA_SP5"
"39","(-1800,3500)","0","pure_quanta","I4";
;
LOCATION"U26"
$SEC"39"
CDS_SEC"39"
PART_TYPE"SMLF"
MATERIAL"IO"
VALUE"SOCKET6096_13568-001"
PART_NUMBER"DGA^6000030"
CDS_LIB"pure_quanta"
CDS_LMAN_SYM_OUTLINE"-400,3050,400,-3050"
NEEDS_NO_SIZE"TRUE";
"VSS_DA70"
$PN"DA70"7;
"VSS_DA68"
$PN"DA68"7;
"VSS_DA65"
$PN"DA65"7;
"VSS_DA63"
$PN"DA63"7;
"VSS_DA61"
$PN"DA61"7;
"VSS_DA58"
$PN"DA58"7;
"VSS_DA42"
$PN"DA42"7;
"VSS_DA34"
$PN"DA34"7;
"VSS_DA31"
$PN"DA31"7;
"VSS_DA28"
$PN"DA28"7;
"VSS_DA25"
$PN"DA25"7;
"VSS_DA22"
$PN"DA22"7;
"VSS_DA11"
$PN"DA11"7;
"VSS_DA8"
$PN"DA8"7;
"VSS_DA6"
$PN"DA6"7;
"VSS_DA4"
$PN"DA4"7;
"VSS_DA1"
$PN"DA1"7;
"VSS_CY73"
$PN"CY73"7;
"VSS_CY71"
$PN"CY71"7;
"VSS_CY61"
$PN"CY61"7;
"VSS_CY59"
$PN"CY59"7;
"VSS_CY53"
$PN"CY53"7;
"VSS_CY52"
$PN"CY52"7;
"VSS_CY51"
$PN"CY51"7;
"VSS_CY50"
$PN"CY50"7;
"VSS_CY49"
$PN"CY49"7;
"VSS_CY46"
$PN"CY46"7;
"VSS_CY45"
$PN"CY45"7;
"VSS_CY44"
$PN"CY44"7;
"VSS_CY43"
$PN"CY43"7;
"VSS_CY42"
$PN"CY42"7;
"VSS_CY39"
$PN"CY39"7;
"VSS_CY37"
$PN"CY37"7;
"VSS_CY34"
$PN"CY34"7;
"VSS_CY33"
$PN"CY33"7;
"VSS_CY31"
$PN"CY31"7;
"VSS_CY30"
$PN"CY30"7;
"VSS_CY29"
$PN"CY29"7;
"VSS_CY28"
$PN"CY28"7;
"VSS_CY27"
$PN"CY27"7;
"VSS_CY26"
$PN"CY26"7;
"VSS_CY25"
$PN"CY25"7;
"VSS_CY24"
$PN"CY24"7;
"VSS_CY23"
$PN"CY23"7;
"VSS_CY19"
$PN"CY19"7;
"VSS_CY17"
$PN"CY17"7;
"VSS_CY15"
$PN"CY15"7;
"VSS_CY12"
$PN"CY12"7;
"VSS_CY10"
$PN"CY10"7;
"VSS_CY8"
$PN"CY8"7;
"VSS_CY5"
$PN"CY5"7;
"VSS_CY3"
$PN"CY3"7;
"VSS_CW75"
$PN"CW75"7;
"VSS_CW70"
$PN"CW70"7;
"VSS_CW68"
$PN"CW68"7;
"VSS_CW63"
$PN"CW63"7;
"VSS_CW61"
$PN"CW61"7;
"VSS_CW56"
$PN"CW56"7;
"VSS_CW54"
$PN"CW54"7;
"VSS_CW51"
$PN"CW51"7;
"VSS_CW48"
$PN"CW48"7;
"VSS_CW45"
$PN"CW45"7;
"VSS_CW42"
$PN"CW42"7;
"VSS_CW41"
$PN"CW41"7;
"VSS_CW40"
$PN"CW40"7;
"VSS_CW36"
$PN"CW36"7;
"VSS_CW35"
$PN"CW35"7;
"VSS_CW20"
$PN"CW20"7;
"VSS_CW15"
$PN"CW15"7;
"VSS_CW13"
$PN"CW13"7;
"VSS_CW8"
$PN"CW8"7;
"VSS_CW6"
$PN"CW6"7;
"VSS_CW1"
$PN"CW1"7;
"VSS_CV61"
$PN"CV61"7;
"VSS_CV59"
$PN"CV59"7;
"VSS_CV57"
$PN"CV57"7;
"VSS_CV54"
$PN"CV54"7;
"VSS_CV51"
$PN"CV51"7;
"VSS_CV48"
$PN"CV48"7;
"VSS_CV31"
$PN"CV31"7;
"VSS_CV28"
$PN"CV28"7;
"VSS_CV25"
$PN"CV25"7;
"VSS_CV22"
$PN"CV22"7;
"VSS_CV19"
$PN"CV19"7;
"VSS_CV17"
$PN"CV17"7;
"VSS_CV3"
$PN"CV3"8;
"VSS_CU75"
$PN"CU75"8;
"VSS_CU72"
$PN"CU72"8;
"VSS_CU70"
$PN"CU70"8;
"VSS_CU68"
$PN"CU68"8;
"VSS_CU65"
$PN"CU65"8;
"VSS_CU54"
$PN"CU54"8;
"VSS_CU51"
$PN"CU51"8;
"VSS_CU48"
$PN"CU48"8;
"VSS_CU45"
$PN"CU45"8;
"VSS_CU42"
$PN"CU42"8;
"VSS_CU34"
$PN"CU34"8;
"VSS_CU31"
$PN"CU31"8;
"VSS_CU20"
$PN"CU20"8;
"VSS_CU18"
$PN"CU18"8;
"VSS_CU15"
$PN"CU15"8;
"VSS_CU13"
$PN"CU13"8;
"VSS_CU11"
$PN"CU11"8;
"VSS_CU8"
$PN"CU8"8;
"VSS_CU6"
$PN"CU6"8;
"VSS_CU4"
$PN"CU4"8;
"VSS_CT68"
$PN"CT68"8;
"VSS_CT66"
$PN"CT66"8;
"VSS_CT61"
$PN"CT61"8;
"VSS_CT59"
$PN"CT59"8;
"VSS_CT53"
$PN"CT53"8;
"VSS_CT51"
$PN"CT51"8;
"VSS_CT50"
$PN"CT50"8;
"VSS_CT49"
$PN"CT49"8;
"VSS_CT47"
$PN"CT47"8;
"VSS_CT46"
$PN"CT46"8;
"VSS_CT45"
$PN"CT45"8;
"VSS_CT44"
$PN"CT44"8;
"VSS_CT43"
$PN"CT43"8;
"VSS_CT42"
$PN"CT42"8;
"VSS_CT39"
$PN"CT39"8;
"VSS_CT37"
$PN"CT37"8;
"VSS_CT34"
$PN"CT34"8;
"VSS_CT33"
$PN"CT33"8;
"VSS_CT32"
$PN"CT32"8;
"VSS_CT31"
$PN"CT31"8;
"VSS_CT30"
$PN"CT30"8;
"VSS_CT29"
$PN"CT29"8;
"VSS_CT28"
$PN"CT28"8;
"VSS_CT27"
$PN"CT27"8;
"VSS_CT26"
$PN"CT26"8;
"VSS_CT25"
$PN"CT25"8;
"VSS_CT24"
$PN"CT24"8;
"VSS_CT23"
$PN"CT23"8;
"VSS_CT17"
$PN"CT17"8;
"VSS_CR72"
$PN"CR72"8;
"VSS_CR70"
$PN"CR70"8;
"VSS_CR68"
$PN"CR68"8;
"VSS_CR65"
$PN"CR65"8;
"VSS_CR63"
$PN"CR63"8;
"VSS_CR61"
$PN"CR61"8;
"VSS_CR45"
$PN"CR45"8;
"VSS_CR42"
$PN"CR42"8;
"VSS_CR41"
$PN"CR41"8;
"VSS_CR40"
$PN"CR40"8;
"VSS_CR36"
$PN"CR36"8;
"VSS_CR35"
$PN"CR35"8;
"VSS_CR20"
$PN"CR20"8;
"VSS_CR18"
$PN"CR18"8;
"VSS_CR15"
$PN"CR15"8;
"VSS_CR13"
$PN"CR13"8;
"VSS_CR11"
$PN"CR11"8;
"VSS_CR8"
$PN"CR8"8;
"VSS_CP68"
$PN"CP68"8;
"VSS_CP66"
$PN"CP66"8;
"VSS_CP64"
$PN"CP64"8;
"VSS_CP61"
$PN"CP61"8;
"VSS_CP59"
$PN"CP59"8;
"VSS_CP57"
$PN"CP57"8;
"VSS_CP39"
$PN"CP39"8;
"VSS_CP37"
$PN"CP37"8;
"VSS_CP34"
$PN"CP34"8;
"VSS_CP31"
$PN"CP31"8;
"VSS_CP28"
$PN"CP28"8;
"VSS_CP25"
$PN"CP25"8;
"VSS_DA54"
$PN"DA54"7;
"VSS_DA51"
$PN"DA51"7;
"VSS_DA48"
$PN"DA48"7;
"VSS_DA45"
$PN"DA45"7;
"VSS_DA20"
$PN"DA20"7;
"VSS_DA18"
$PN"DA18"7;
"VSS_DA15"
$PN"DA15"7;
"VSS_DA13"
$PN"DA13"7;
"VSS_CY68"
$PN"CY68"7;
"VSS_CY66"
$PN"CY66"7;
"VSS_CY64"
$PN"CY64"7;
"VSS_CY48"
$PN"CY48"7;
"VSS_CY47"
$PN"CY47"7;
"VSS_CY32"
$PN"CY32"7;
"VSS_CW34"
$PN"CW34"7;
"VSS_CW31"
$PN"CW31"7;
"VSS_CW28"
$PN"CW28"7;
"VSS_CW25"
$PN"CW25"7;
"VSS_CW22"
$PN"CW22"7;
"VSS_CV73"
$PN"CV73"7;
"VSS_CV71"
$PN"CV71"7;
"VSS_CV68"
$PN"CV68"7;
"VSS_CV66"
$PN"CV66"7;
"VSS_CV64"
$PN"CV64"7;
"VSS_CV45"
$PN"CV45"7;
"VSS_CV42"
$PN"CV42"7;
"VSS_CV39"
$PN"CV39"7;
"VSS_CV37"
$PN"CV37"7;
"VSS_CV34"
$PN"CV34"7;
"VSS_CV15"
$PN"CV15"7;
"VSS_CV12"
$PN"CV12"7;
"VSS_CV10"
$PN"CV10"7;
"VSS_CV8"
$PN"CV8"8;
"VSS_CV5"
$PN"CV5"8;
"VSS_CU63"
$PN"CU63"8;
"VSS_CU61"
$PN"CU61"8;
"VSS_CU56"
$PN"CU56"8;
"VSS_CU28"
$PN"CU28"8;
"VSS_CU25"
$PN"CU25"8;
"VSS_CU22"
$PN"CU22"8;
"VSS_CU1"
$PN"CU1"8;
"VSS_CT73"
$PN"CT73"8;
"VSS_CT48"
$PN"CT48"8;
"VSS_CT15"
$PN"CT15"8;
"VSS_CT10"
$PN"CT10"8;
"VSS_CT8"
$PN"CT8"8;
"VSS_CT3"
$PN"CT3"8;
"VSS_CR75"
$PN"CR75"8;
"VSS_CR58"
$PN"CR58"8;
"VSS_CR56"
$PN"CR56"8;
"VSS_CR54"
$PN"CR54"8;
"VSS_CR51"
$PN"CR51"8;
"VSS_CR48"
$PN"CR48"8;
"VSS_CR34"
$PN"CR34"8;
"VSS_CR31"
$PN"CR31"8;
"VSS_CR28"
$PN"CR28"8;
"VSS_CR25"
$PN"CR25"8;
"VSS_CR22"
$PN"CR22"8;
"VSS_CR6"
$PN"CR6"8;
"VSS_CR4"
$PN"CR4"8;
"VSS_CR1"
$PN"CR1"8;
"VSS_CP73"
$PN"CP73"8;
"VSS_CP71"
$PN"CP71"8;
"VSS_CP54"
$PN"CP54"8;
"VSS_CP51"
$PN"CP51"8;
"VSS_CP48"
$PN"CP48"8;
"VSS_CP45"
$PN"CP45"8;
"VSS_CP42"
$PN"CP42"8;
"VSS_CP22"
$PN"CP22"8;
%"UNIVERSAL_GND"
"1","(-1075,450)","0","pure_quanta_power","I5";
;
CDS_LIB"pure_quanta_power"
HDL_POWER"GND";
"A"8;
%"UNIVERSAL_GND"
"1","(-2525,450)","0","pure_quanta_power","I6";
;
CDS_LIB"pure_quanta_power"
HDL_POWER"GND";
"A"7;
%"UNIVERSAL_GND"
"1","(-3150,450)","0","pure_quanta_power","I7";
;
CDS_LIB"pure_quanta_power"
HDL_POWER"GND";
"A"6;
%"UNIVERSAL_GND"
"1","(-4600,475)","0","pure_quanta_power","I8";
;
CDS_LIB"pure_quanta_power"
HDL_POWER"GND";
"A"5;
%"UNIVERSAL_GND"
"1","(-5225,475)","0","pure_quanta_power","I9";
;
CDS_LIB"pure_quanta_power"
HDL_POWER"GND";
"A"4;
END.
